# S9S_MB_2U (Grand Teton) — schematic netlist excerpt (pin names and nets, part order shuffled) for the footprints in the layout excerpt that follows; sources: Cadence DE-HDL packaged netlist, KiCad conversion of 03242023_DA0F0TMBIJ0_F0T_Motherboard_J_brd_V01_OCP.brd

C1860  Q_CAP  0.1UF 25V 10% X7R  pkg 0402  page 238 : A = P3V3_AUX ; B = GND
C1958  Q_CAP  0.1UF 25V 10% X7R  pkg 0402  page 149 : A = P3V3_AUX ; B = GND

(kicad_pcb
	(version 20260206)
	(generator "pcbnew")
	(generator_version "10.0")
	(general
		(thickness 1.6)
		(legacy_teardrops no)
	)
	(paper "A4")
	(title_block
		(title "03242023_DA0F0TMBIJ0_F0T_Motherboard_J_brd_V01_OCP.brd")
		(comment 1 "Grand Teton / footprints 3103-3104 of 6105")
	)
	(layers
		(0 "F.Cu" signal "TOP")
		(4 "In1.Cu" signal "GND")
		(6 "In2.Cu" signal "IN1")
		(8 "In3.Cu" signal "GND1")
		(10 "In4.Cu" signal "IN2")
		(12 "In5.Cu" signal "GND2")
		(14 "In6.Cu" signal "IN3")
		(16 "In7.Cu" signal "GND3")
		(18 "In8.Cu" signal "VCC")
		(20 "In9.Cu" signal "VCC1")
		(22 "In10.Cu" signal "GND4")
		(24 "In11.Cu" signal "IN4")
		(26 "In12.Cu" signal "GND5")
		(28 "In13.Cu" signal "IN5")
		(30 "In14.Cu" signal "GND6")
		(32 "In15.Cu" signal "IN6")
		(34 "In16.Cu" signal "GND7")
		(2 "B.Cu" signal "BOTTOM")
		(9 "F.Adhes" user "F.Adhesive")
		(11 "B.Adhes" user "B.Adhesive")
		(13 "F.Paste" user "Package Geometry/Pastemask Top")
		(15 "B.Paste" user "Package Geometry/Pastemask Bottom")
		(5 "F.SilkS" user "Ref Des/Silkscreen Top")
		(7 "B.SilkS" user "Ref Des/Silkscreen Bottom")
		(1 "F.Mask" user "Board Geometry/Soldermask Top")
		(3 "B.Mask" user "Board Geometry/Soldermask Bottom")
		(17 "Dwgs.User" user "User.Drawings")
		(19 "Cmts.User" user "User.Comments")
		(21 "Eco1.User" user "User.Eco1")
		(23 "Eco2.User" user "User.Eco2")
		(25 "Edge.Cuts" user "Board Geometry/Outline")
		(27 "Margin" user)
		(31 "F.CrtYd" user "Package Geometry/Place Bound Top")
		(29 "B.CrtYd" user "Package Geometry/Place Bound Bottom")
		(35 "F.Fab" user "Ref Des/Assembly Top")
		(33 "B.Fab" user "Ref Des/Assembly Bottom")
	)
	(footprint ""
		(layer "F.Cu")
		(at 438.920636 -46.033436 180)
		(property "Reference" "C1860"
			(at 0 0 180)
			(layer "F.SilkS")
			(hide yes)
			(effects
				(font
					(size 1.27 1.27)
				)
			)
		)
		(property "Value" ""
			(at 0 0 180)
			(layer "F.Fab")
			(effects
				(font
					(size 1.27 1.27)
				)
			)
		)
		(duplicate_pad_numbers_are_jumpers no)
		(fp_line
			(start 0.7874 0.4064)
			(end -0.7874 0.4064)
			(stroke
				(width 0.1524)
				(type default)
			)
			(layer "F.SilkS")
		)
		(fp_line
			(start 0.7874 -0.4064)
			(end 0.7874 0.4064)
			(stroke
				(width 0.1524)
				(type default)
			)
			(layer "F.SilkS")
		)
		(fp_line
			(start -0.7874 0.4064)
			(end -0.7874 -0.4064)
			(stroke
				(width 0.1524)
				(type default)
			)
			(layer "F.SilkS")
		)
		(fp_line
			(start -0.7874 -0.4064)
			(end 0.7874 -0.4064)
			(stroke
				(width 0.1524)
				(type default)
			)
			(layer "F.SilkS")
		)
		(fp_line
			(start 0.67945 0.3048)
			(end 0.120396 0.3048)
			(stroke
				(width 0.1)
				(type default)
			)
			(layer "F.Fab")
		)
		(fp_line
			(start 0.67945 -0.3048)
			(end 0.67945 0.3048)
			(stroke
				(width 0.1)
				(type default)
			)
			(layer "F.Fab")
		)
		(fp_line
			(start 0.12065 -0.2794)
			(end 0.12065 -0.3048)
			(stroke
				(width 0.1)
				(type default)
			)
			(layer "F.Fab")
		)
		(fp_line
			(start 0.12065 -0.3048)
			(end 0.67945 -0.3048)
			(stroke
				(width 0.1)
				(type default)
			)
			(layer "F.Fab")
		)
		(fp_line
			(start 0.120396 0.3048)
			(end 0.120396 0.2794)
			(stroke
				(width 0.1)
				(type default)
			)
			(layer "F.Fab")
		)
		(fp_line
			(start 0.120396 0.2794)
			(end -0.12065 0.2794)
			(stroke
				(width 0.1)
				(type default)
			)
			(layer "F.Fab")
		)
		(fp_line
			(start -0.12065 0.3048)
			(end -0.67945 0.3048)
			(stroke
				(width 0.1)
				(type default)
			)
			(layer "F.Fab")
		)
		(fp_line
			(start -0.12065 0.2794)
			(end -0.12065 0.3048)
			(stroke
				(width 0.1)
				(type default)
			)
			(layer "F.Fab")
		)
		(fp_line
			(start -0.12065 -0.2794)
			(end 0.12065 -0.2794)
			(stroke
				(width 0.1)
				(type default)
			)
			(layer "F.Fab")
		)
		(fp_line
			(start -0.12065 -0.305054)
			(end -0.12065 -0.2794)
			(stroke
				(width 0.1)
				(type default)
			)
			(layer "F.Fab")
		)
		(fp_line
			(start -0.67945 0.3048)
			(end -0.67945 -0.305054)
			(stroke
				(width 0.1)
				(type default)
			)
			(layer "F.Fab")
		)
		(fp_line
			(start -0.67945 -0.305054)
			(end -0.12065 -0.305054)
			(stroke
				(width 0.1)
				(type default)
			)
			(layer "F.Fab")
		)
		(pad "1" smd circle
			(at -0.40005 0 180)
			(size 0 0)
			(layers "F.Cu" "F.Mask" "F.Paste")
			(net "P3V3_AUX")
		)
		(pad "2" smd circle
			(at 0.40005 0 180)
			(size 0 0)
			(layers "F.Cu" "F.Mask" "F.Paste")
			(net "GND")
		)
	)
	(footprint ""
		(layer "F.Cu")
		(at 168.96588 -436.971948)
		(property "Reference" "C1958"
			(at 0 0 0)
			(layer "F.SilkS")
			(hide yes)
			(effects
				(font
					(size 1.27 1.27)
				)
			)
		)
		(property "Value" ""
			(at 0 0 0)
			(layer "F.Fab")
			(effects
				(font
					(size 1.27 1.27)
				)
			)
		)
		(duplicate_pad_numbers_are_jumpers no)
		(fp_line
			(start -0.7874 -0.4064)
			(end 0.7874 -0.4064)
			(stroke
				(width 0.1524)
				(type default)
			)
			(layer "F.SilkS")
		)
		(fp_line
			(start -0.7874 0.4064)
			(end -0.7874 -0.4064)
			(stroke
				(width 0.1524)
				(type default)
			)
			(layer "F.SilkS")
		)
		(fp_line
			(start 0.7874 -0.4064)
			(end 0.7874 0.4064)
			(stroke
				(width 0.1524)
				(type default)
			)
			(layer "F.SilkS")
		)
		(fp_line
			(start 0.7874 0.4064)
			(end -0.7874 0.4064)
			(stroke
				(width 0.1524)
				(type default)
			)
			(layer "F.SilkS")
		)
		(fp_line
			(start -0.67945 -0.305054)
			(end -0.12065 -0.305054)
			(stroke
				(width 0.1)
				(type default)
			)
			(layer "F.Fab")
		)
		(fp_line
			(start -0.67945 0.3048)
			(end -0.67945 -0.305054)
			(stroke
				(width 0.1)
				(type default)
			)
			(layer "F.Fab")
		)
		(fp_line
			(start -0.12065 -0.305054)
			(end -0.12065 -0.2794)
			(stroke
				(width 0.1)
				(type default)
			)
			(layer "F.Fab")
		)
		(fp_line
			(start -0.12065 -0.2794)
			(end 0.12065 -0.2794)
			(stroke
				(width 0.1)
				(type default)
			)
			(layer "F.Fab")
		)
		(fp_line
			(start -0.12065 0.2794)
			(end -0.12065 0.3048)
			(stroke
				(width 0.1)
				(type default)
			)
			(layer "F.Fab")
		)
		(fp_line
			(start -0.12065 0.3048)
			(end -0.67945 0.3048)
			(stroke
				(width 0.1)
				(type default)
			)
			(layer "F.Fab")
		)
		(fp_line
			(start 0.120396 0.2794)
			(end -0.12065 0.2794)
			(stroke
				(width 0.1)
				(type default)
			)
			(layer "F.Fab")
		)
		(fp_line
			(start 0.120396 0.3048)
			(end 0.120396 0.2794)
			(stroke
				(width 0.1)
				(type default)
			)
			(layer "F.Fab")
		)
		(fp_line
			(start 0.12065 -0.3048)
			(end 0.67945 -0.3048)
			(stroke
				(width 0.1)
				(type default)
			)
			(layer "F.Fab")
		)
		(fp_line
			(start 0.12065 -0.2794)
			(end 0.12065 -0.3048)
			(stroke
				(width 0.1)
				(type default)
			)
			(layer "F.Fab")
		)
		(fp_line
			(start 0.67945 -0.3048)
			(end 0.67945 0.3048)
			(stroke
				(width 0.1)
				(type default)
			)
			(layer "F.Fab")
		)
		(fp_line
			(start 0.67945 0.3048)
			(end 0.120396 0.3048)
			(stroke
				(width 0.1)
				(type default)
			)
			(layer "F.Fab")
		)
		(pad "1" smd circle
			(at -0.40005 0)
			(size 0 0)
			(layers "F.Cu" "F.Mask" "F.Paste")
			(net "P3V3_AUX")
		)
		(pad "2" smd circle
			(at 0.40005 0)
			(size 0 0)
			(layers "F.Cu" "F.Mask" "F.Paste")
			(net "GND")
		)
	)
)
